# BASEBOARD_FAB2 (Tioga Pass) — schematic netlist excerpt (pin names and nets, part order shuffled) for the footprints in the layout excerpt that follows; sources: Cadence DE-HDL packaged netlist, KiCad conversion of Wiwynn_Tioga_Pass_MB.brd

R1G8  RES  33.2 1% CHIP  pkg 0402  page 223 : A = IRQ_PVDDQ_GHJ_VRHOT_LVT3_R_N ; B = IRQ_PVDDQ_GHJ_VRHOT_LVT3_N
CT60  CAP_A  0.1UF 16V 10% X7R  pkg 0402V  page 205 : A = VR_PVSA_CPU0_BIREF1 ; B = GND
R2U3  RES  665 1.0% CHIP  pkg 0402  page 138 : A = P3V3_STBY ; B = SMB_LAN_STBY_LVC3_SCL

(kicad_pcb
	(version 20260206)
	(generator "pcbnew")
	(generator_version "10.0")
	(general
		(thickness 1.6)
		(legacy_teardrops no)
	)
	(paper "A4")
	(title_block
		(title "Wiwynn_Tioga_Pass_MB.brd")
		(comment 1 "Tioga Pass / footprints 89-91 of 4770")
	)
	(layers
		(0 "F.Cu" signal "TOP")
		(4 "In1.Cu" signal "L2GND")
		(6 "In2.Cu" signal "L3")
		(8 "In3.Cu" signal "L4GND")
		(10 "In4.Cu" signal "L5")
		(12 "In5.Cu" signal "L6GND")
		(14 "In6.Cu" signal "L7VCC")
		(16 "In7.Cu" signal "L8VCC")
		(18 "In8.Cu" signal "L9GND")
		(20 "In9.Cu" signal "L10")
		(22 "In10.Cu" signal "L11GND")
		(24 "In11.Cu" signal "L12")
		(26 "In12.Cu" signal "L13GND")
		(2 "B.Cu" signal "BOTTOM")
		(9 "F.Adhes" user "F.Adhesive")
		(11 "B.Adhes" user "B.Adhesive")
		(13 "F.Paste" user "Package Geometry/Pastemask Top")
		(15 "B.Paste" user "Package Geometry/Pastemask Bottom")
		(5 "F.SilkS" user "Ref Des/Silkscreen Top")
		(7 "B.SilkS" user "Ref Des/Silkscreen Bottom")
		(1 "F.Mask" user "Board Geometry/Soldermask Top")
		(3 "B.Mask" user "Board Geometry/Soldermask Bottom")
		(17 "Dwgs.User" user "User.Drawings")
		(19 "Cmts.User" user "User.Comments")
		(21 "Eco1.User" user "User.Eco1")
		(23 "Eco2.User" user "User.Eco2")
		(25 "Edge.Cuts" user "Board Geometry/Outline")
		(27 "Margin" user)
		(31 "F.CrtYd" user "Package Geometry/Place Bound Top")
		(29 "B.CrtYd" user "Package Geometry/Place Bound Bottom")
		(35 "F.Fab" user "Ref Des/Assembly Top")
		(33 "B.Fab" user "Ref Des/Assembly Bottom")
	)
	(footprint ""
		(layer "F.Cu")
		(at 14.209268 -3.54203 180)
		(property "Reference" "R1G8"
			(at 0 0 180)
			(layer "F.SilkS")
			(hide yes)
			(effects
				(font
					(size 1.27 1.27)
				)
			)
		)
		(property "Value" ""
			(at 0 0 180)
			(layer "F.Fab")
			(effects
				(font
					(size 1.27 1.27)
				)
			)
		)
		(duplicate_pad_numbers_are_jumpers no)
		(fp_poly
			(pts
				(xy -0.2794 -0.1016) (xy 0.2794 -0.1016) (xy 0.2794 0.9906) (xy -0.2794 0.9906)
			)
			(stroke
				(width 0)
				(type default)
			)
			(fill no)
			(layer "F.CrtYd")
		)
		(fp_line
			(start 0.2794 0.9906)
			(end 0.2794 -0.1016)
			(stroke
				(width 0.1)
				(type default)
			)
			(layer "F.Fab")
		)
		(fp_line
			(start 0.2794 -0.1016)
			(end -0.2794 -0.1016)
			(stroke
				(width 0.1)
				(type default)
			)
			(layer "F.Fab")
		)
		(fp_line
			(start -0.2794 0.9906)
			(end 0.2794 0.9906)
			(stroke
				(width 0.1)
				(type default)
			)
			(layer "F.Fab")
		)
		(fp_line
			(start -0.2794 -0.1016)
			(end -0.2794 0.9906)
			(stroke
				(width 0.1)
				(type default)
			)
			(layer "F.Fab")
		)
		(pad "1" smd rect
			(at 0 0 180)
			(size 0.508 0.508)
			(layers "F.Cu" "F.Mask" "F.Paste")
			(net "IRQ_PVDDQ_GHJ_VRHOT_LVT3_R_N")
		)
		(pad "2" smd rect
			(at 0 0.889 180)
			(size 0.508 0.508)
			(layers "F.Cu" "F.Mask" "F.Paste")
			(net "IRQ_PVDDQ_GHJ_VRHOT_LVT3_N")
		)
		(zone
			(layer "F.Cu")
			(hatch none 0.5)
			(connect_pads
				(clearance 0)
			)
			(min_thickness 0.25)
			(keepout
				(tracks not_allowed)
				(vias allowed)
				(pads allowed)
				(copperpour not_allowed)
				(footprints allowed)
			)
			(placement
				(enabled no)
				(sheetname "")
			)
			(fill
				(thermal_gap 0.5)
				(thermal_bridge_width 0.5)
				(island_removal_mode 0)
			)
			(polygon
				(pts
					(xy 14.463268 -4.17703) (xy 13.955268 -4.17703) (xy 13.955268 -3.79603) (xy 14.463268 -3.79603)
				)
			)
		)
		(zone
			(layer "F.Cu")
			(hatch none 0.5)
			(connect_pads
				(clearance 0)
			)
			(min_thickness 0.25)
			(keepout
				(tracks allowed)
				(vias not_allowed)
				(pads allowed)
				(copperpour not_allowed)
				(footprints allowed)
			)
			(placement
				(enabled no)
				(sheetname "")
			)
			(fill
				(thermal_gap 0.5)
				(thermal_bridge_width 0.5)
				(island_removal_mode 0)
			)
			(polygon
				(pts
					(xy 14.463268 -3.79603) (xy 13.955268 -3.79603) (xy 13.955268 -4.17703) (xy 14.463268 -4.17703)
				)
			)
		)
	)
	(footprint ""
		(layer "F.Cu")
		(at 195.086986 -94.687898)
		(property "Reference" "CT60"
			(at 1.8288 -2.28473 0)
			(unlocked yes)
			(layer "F.SilkS")
			(effects
				(font
					(size 0.7874 0.5842)
					(thickness 0.1524)
				)
				(justify left)
			)
		)
		(property "Value" ""
			(at 0 0 0)
			(layer "F.Fab")
			(effects
				(font
					(size 1.27 1.27)
				)
			)
		)
		(duplicate_pad_numbers_are_jumpers no)
		(fp_poly
			(pts
				(xy 0.3048 -0.1016) (xy 0.3048 0.9906) (xy -0.3048 0.9906) (xy -0.3048 -0.1016)
			)
			(stroke
				(width 0)
				(type default)
			)
			(fill no)
			(layer "F.CrtYd")
		)
		(fp_line
			(start -0.3048 -0.1016)
			(end -0.3048 0.9906)
			(stroke
				(width 0.1)
				(type default)
			)
			(layer "F.Fab")
		)
		(fp_line
			(start -0.3048 0.9906)
			(end 0.3048 0.9906)
			(stroke
				(width 0.1)
				(type default)
			)
			(layer "F.Fab")
		)
		(fp_line
			(start 0.3048 -0.1016)
			(end -0.3048 -0.1016)
			(stroke
				(width 0.1)
				(type default)
			)
			(layer "F.Fab")
		)
		(fp_line
			(start 0.3048 0.9906)
			(end 0.3048 -0.1016)
			(stroke
				(width 0.1)
				(type default)
			)
			(layer "F.Fab")
		)
		(pad "1" smd rect
			(at 0 0)
			(size 0.508 0.508)
			(layers "F.Cu" "F.Mask" "F.Paste")
			(net "VR_PVSA_CPU0_BIREF1")
		)
		(pad "2" smd rect
			(at 0 0.889)
			(size 0.508 0.508)
			(layers "F.Cu" "F.Mask" "F.Paste")
			(net "GND")
		)
		(zone
			(layer "F.Cu")
			(hatch none 0.5)
			(connect_pads
				(clearance 0)
			)
			(min_thickness 0.25)
			(keepout
				(tracks allowed)
				(vias not_allowed)
				(pads allowed)
				(copperpour not_allowed)
				(footprints allowed)
			)
			(placement
				(enabled no)
				(sheetname "")
			)
			(fill
				(thermal_gap 0.5)
				(thermal_bridge_width 0.5)
				(island_removal_mode 0)
			)
			(polygon
				(pts
					(xy 194.832986 -94.433898) (xy 195.340986 -94.433898) (xy 195.340986 -94.052898) (xy 194.832986 -94.052898)
				)
			)
		)
		(zone
			(layer "F.Cu")
			(hatch none 0.5)
			(connect_pads
				(clearance 0)
			)
			(min_thickness 0.25)
			(keepout
				(tracks not_allowed)
				(vias allowed)
				(pads allowed)
				(copperpour not_allowed)
				(footprints allowed)
			)
			(placement
				(enabled no)
				(sheetname "")
			)
			(fill
				(thermal_gap 0.5)
				(thermal_bridge_width 0.5)
				(island_removal_mode 0)
			)
			(polygon
				(pts
					(xy 194.832986 -94.052898) (xy 195.340986 -94.052898) (xy 195.340986 -94.433898) (xy 194.832986 -94.433898)
				)
			)
		)
	)
	(footprint ""
		(layer "F.Cu")
		(at 395.351 -85.0265 180)
		(property "Reference" "R2U3"
			(at 0 0 180)
			(layer "F.SilkS")
			(hide yes)
			(effects
				(font
					(size 1.27 1.27)
				)
			)
		)
		(property "Value" ""
			(at 0 0 180)
			(layer "F.Fab")
			(effects
				(font
					(size 1.27 1.27)
				)
			)
		)
		(duplicate_pad_numbers_are_jumpers no)
		(fp_poly
			(pts
				(xy -0.2794 -0.1016) (xy 0.2794 -0.1016) (xy 0.2794 0.9906) (xy -0.2794 0.9906)
			)
			(stroke
				(width 0)
				(type default)
			)
			(fill no)
			(layer "F.CrtYd")
		)
		(fp_line
			(start 0.2794 0.9906)
			(end 0.2794 -0.1016)
			(stroke
				(width 0.1)
				(type default)
			)
			(layer "F.Fab")
		)
		(fp_line
			(start 0.2794 -0.1016)
			(end -0.2794 -0.1016)
			(stroke
				(width 0.1)
				(type default)
			)
			(layer "F.Fab")
		)
		(fp_line
			(start -0.2794 0.9906)
			(end 0.2794 0.9906)
			(stroke
				(width 0.1)
				(type default)
			)
			(layer "F.Fab")
		)
		(fp_line
			(start -0.2794 -0.1016)
			(end -0.2794 0.9906)
			(stroke
				(width 0.1)
				(type default)
			)
			(layer "F.Fab")
		)
		(pad "1" smd rect
			(at 0 0 180)
			(size 0.508 0.508)
			(layers "F.Cu" "F.Mask" "F.Paste")
			(net "P3V3_STBY")
		)
		(pad "2" smd rect
			(at 0 0.889 180)
			(size 0.508 0.508)
			(layers "F.Cu" "F.Mask" "F.Paste")
			(net "SMB_LAN_STBY_LVC3_SCL")
		)
		(zone
			(layer "F.Cu")
			(hatch none 0.5)
			(connect_pads
				(clearance 0)
			)
			(min_thickness 0.25)
			(keepout
				(tracks not_allowed)
				(vias allowed)
				(pads allowed)
				(copperpour not_allowed)
				(footprints allowed)
			)
			(placement
				(enabled no)
				(sheetname "")
			)
			(fill
				(thermal_gap 0.5)
				(thermal_bridge_width 0.5)
				(island_removal_mode 0)
			)
			(polygon
				(pts
					(xy 395.605 -85.6615) (xy 395.097 -85.6615) (xy 395.097 -85.2805) (xy 395.605 -85.2805)
				)
			)
		)
		(zone
			(layer "F.Cu")
			(hatch none 0.5)
			(connect_pads
				(clearance 0)
			)
			(min_thickness 0.25)
			(keepout
				(tracks allowed)
				(vias not_allowed)
				(pads allowed)
				(copperpour not_allowed)
				(footprints allowed)
			)
			(placement
				(enabled no)
				(sheetname "")
			)
			(fill
				(thermal_gap 0.5)
				(thermal_bridge_width 0.5)
				(island_removal_mode 0)
			)
			(polygon
				(pts
					(xy 395.605 -85.2805) (xy 395.097 -85.2805) (xy 395.097 -85.6615) (xy 395.605 -85.6615)
				)
			)
		)
	)
)
